(kicad_pcb
	(version 20260206)
	(generator "pcbnew")
	(generator_version "10.0")
	(general
		(thickness 1.6)
		(legacy_teardrops no)
	)
	(paper "A4")
	(title_block
		(title "Bryce Canyon_F.DPB_16315-1-OCP.brd")
		(comment 1 "Bryce Canyon / footprints 1132-1138 of 2223")
	)
	(layers
		(0 "F.Cu" signal "TOP")
		(4 "In1.Cu" signal "L2GND")
		(6 "In2.Cu" signal "L3")
		(8 "In3.Cu" signal "L4GND")
		(10 "In4.Cu" signal "L5")
		(12 "In5.Cu" signal "L6VCC")
		(14 "In6.Cu" signal "L7VCC")
		(16 "In7.Cu" signal "L8")
		(18 "In8.Cu" signal "L9GND")
		(20 "In9.Cu" signal "L10")
		(22 "In10.Cu" signal "L11GND")
		(2 "B.Cu" signal "BOTTOM")
		(9 "F.Adhes" user "F.Adhesive")
		(11 "B.Adhes" user "B.Adhesive")
		(13 "F.Paste" user "Package Geometry/Pastemask Top")
		(15 "B.Paste" user "Package Geometry/Pastemask Bottom")
		(5 "F.SilkS" user "Ref Des/Silkscreen Top")
		(7 "B.SilkS" user "Ref Des/Silkscreen Bottom")
		(1 "F.Mask" user "Board Geometry/Soldermask Top")
		(3 "B.Mask" user "Board Geometry/Soldermask Bottom")
		(17 "Dwgs.User" user "User.Drawings")
		(19 "Cmts.User" user "User.Comments")
		(21 "Eco1.User" user "User.Eco1")
		(23 "Eco2.User" user "User.Eco2")
		(25 "Edge.Cuts" user "Board Geometry/Outline")
		(27 "Margin" user)
		(31 "F.CrtYd" user "Package Geometry/Place Bound Top")
		(29 "B.CrtYd" user "Package Geometry/Place Bound Bottom")
		(35 "F.Fab" user "Ref Des/Assembly Top")
		(33 "B.Fab" user "Ref Des/Assembly Bottom")
	)
	(footprint ""
		(layer "F.Cu")
		(at 130.828796 -180.064918 90)
		(property "Reference" "R479"
			(at 0 0 90)
			(layer "F.SilkS")
			(hide yes)
			(effects
				(font
					(size 1.27 1.27)
				)
			)
		)
		(property "Value" "220R3F-1-GP"
			(at -0.0254 -2.5146 90)
			(unlocked yes)
			(layer "F.Fab")
			(hide yes)
			(effects
				(font
					(size 1.016 1.016)
					(thickness 0.1524)
				)
			)
		)
		(property "Device Type" "R603H22"
			(at -0.0254 -4.0386 90)
			(unlocked yes)
			(layer "F.Fab")
			(hide yes)
			(effects
				(font
					(size 1.016 1.016)
					(thickness 0.1524)
				)
			)
		)
		(duplicate_pad_numbers_are_jumpers no)
		(fp_line
			(start 0.2032 0)
			(end 0.4826 0)
			(stroke
				(width 0.2032)
				(type default)
			)
			(layer "F.SilkS")
		)
		(fp_line
			(start -0.4826 0)
			(end -0.2032 0)
			(stroke
				(width 0.2032)
				(type default)
			)
			(layer "F.SilkS")
		)
		(fp_rect
			(start -0.5842 1.3335)
			(end 0.5842 -1.3335)
			(stroke
				(width 0)
				(type default)
			)
			(fill no)
			(layer "F.CrtYd")
		)
		(fp_rect
			(start -0.5842 1.3335)
			(end 0.5842 -1.3335)
			(stroke
				(width 0)
				(type default)
			)
			(fill no)
			(layer "F.Fab")
		)
		(pad "1" smd custom
			(at 0 -0.762 90)
			(size 0.2159 0.2159)
			(layers "F.Cu" "F.Mask" "F.Paste")
			(net "HDD_PRSNT_15")
			(options
				(clearance outline)
				(anchor circle)
			)
			(primitives
				(gr_poly
					(pts
						(arc
							(start -0.3302 -0.4318)
							(mid -0.402042 -0.402042)
							(end -0.4318 -0.3302)
						)
						(arc
							(start -0.4318 0.3302)
							(mid -0.402042 0.402042)
							(end -0.3302 0.4318)
						)
						(arc
							(start 0.3302 0.4318)
							(mid 0.402042 0.402042)
							(end 0.4318 0.3302)
						)
						(arc
							(start 0.4318 -0.3302)
							(mid 0.402042 -0.402042)
							(end 0.3302 -0.4318)
						)
					)
					(width 0)
					(fill yes)
				)
			)
		)
		(pad "2" smd custom
			(at 0 0.762 90)
			(size 0.2159 0.2159)
			(layers "F.Cu" "F.Mask" "F.Paste")
			(net "DRIVE_A_15_INS")
			(options
				(clearance outline)
				(anchor circle)
			)
			(primitives
				(gr_poly
					(pts
						(arc
							(start -0.3302 -0.4318)
							(mid -0.402042 -0.402042)
							(end -0.4318 -0.3302)
						)
						(arc
							(start -0.4318 0.3302)
							(mid -0.402042 0.402042)
							(end -0.3302 0.4318)
						)
						(arc
							(start 0.3302 0.4318)
							(mid 0.402042 0.402042)
							(end 0.4318 0.3302)
						)
						(arc
							(start 0.4318 -0.3302)
							(mid 0.402042 -0.402042)
							(end 0.3302 -0.4318)
						)
					)
					(width 0)
					(fill yes)
				)
			)
		)
	)
	(footprint ""
		(layer "F.Cu")
		(at 457.6699 -73.954894 180)
		(property "Reference" "C486"
			(at 0 0 180)
			(layer "F.SilkS")
			(hide yes)
			(effects
				(font
					(size 1.27 1.27)
				)
			)
		)
		(property "Value" "SC4D7U25V5KX-1-GP"
			(at -0.0762 -6.1214 180)
			(unlocked yes)
			(layer "F.Fab")
			(hide yes)
			(effects
				(font
					(size 1.016 1.016)
					(thickness 0.1524)
				)
			)
		)
		(property "Device Type" "C805H58"
			(at -0.0762 -8.1534 180)
			(unlocked yes)
			(layer "F.Fab")
			(hide yes)
			(effects
				(font
					(size 1.016 1.016)
					(thickness 0.1524)
				)
			)
		)
		(duplicate_pad_numbers_are_jumpers no)
		(fp_line
			(start 0.635 0)
			(end -0.635 0)
			(stroke
				(width 0.508)
				(type default)
			)
			(layer "F.SilkS")
		)
		(fp_rect
			(start -0.9652 1.778)
			(end 0.9652 -1.778)
			(stroke
				(width 0)
				(type default)
			)
			(fill no)
			(layer "F.CrtYd")
		)
		(fp_poly
			(pts
				(xy -0.9652 -1.778) (xy 0.9652 -1.778) (xy 0.9652 1.778) (xy -0.9652 1.778)
			)
			(stroke
				(width 0)
				(type default)
			)
			(fill no)
			(layer "F.Fab")
		)
		(pad "1" smd rect
			(at 0 -0.9652 180)
			(size 1.397 1.143)
			(layers "F.Cu" "F.Mask" "F.Paste")
			(net "P12V_HDD34")
		)
		(pad "2" smd rect
			(at 0 0.9652 180)
			(size 1.397 1.143)
			(layers "F.Cu" "F.Mask" "F.Paste")
			(net "GND")
		)
	)
	(footprint ""
		(layer "F.Cu")
		(at 272.8976 11.184128 180)
		(property "Reference" "R615"
			(at 0 0 180)
			(layer "F.SilkS")
			(hide yes)
			(effects
				(font
					(size 1.27 1.27)
				)
			)
		)
		(property "Value" "10KR2F-2-GP"
			(at 0.064008 -3.993896 180)
			(unlocked yes)
			(layer "F.Fab")
			(hide yes)
			(effects
				(font
					(size 1.016 1.016)
					(thickness 0.1524)
				)
			)
		)
		(property "Device Type" "R402H16"
			(at 0.064008 -5.517896 180)
			(unlocked yes)
			(layer "F.Fab")
			(hide yes)
			(effects
				(font
					(size 1.016 1.016)
					(thickness 0.1524)
				)
			)
		)
		(duplicate_pad_numbers_are_jumpers no)
		(fp_line
			(start 0.508 -0.9398)
			(end -0.508 -0.9398)
			(stroke
				(width 0.1524)
				(type default)
			)
			(layer "F.SilkS")
		)
		(fp_line
			(start -0.508 -0.9398)
			(end -0.508 0.9398)
			(stroke
				(width 0.1524)
				(type default)
			)
			(layer "F.SilkS")
		)
		(fp_rect
			(start -0.508 0.9398)
			(end 0.508 -0.9398)
			(stroke
				(width 0)
				(type default)
			)
			(fill no)
			(layer "F.CrtYd")
		)
		(fp_rect
			(start -0.508 0.9398)
			(end 0.508 -0.9398)
			(stroke
				(width 0)
				(type default)
			)
			(fill no)
			(layer "F.Fab")
		)
		(pad "1" smd custom
			(at 0 -0.4445 180)
			(size 0.1397 0.1397)
			(layers "F.Cu" "F.Mask" "F.Paste")
			(net "IOM_B_FAULT_LED")
			(options
				(clearance outline)
				(anchor circle)
			)
			(primitives
				(gr_poly
					(pts
						(arc
							(start -0.1778 -0.2794)
							(mid -0.249642 -0.249642)
							(end -0.2794 -0.1778)
						)
						(arc
							(start -0.2794 0.1778)
							(mid -0.249642 0.249642)
							(end -0.1778 0.2794)
						)
						(arc
							(start 0.1778 0.2794)
							(mid 0.249642 0.249642)
							(end 0.2794 0.1778)
						)
						(arc
							(start 0.2794 -0.1778)
							(mid 0.249642 -0.249642)
							(end 0.1778 -0.2794)
						)
					)
					(width 0)
					(fill yes)
				)
			)
		)
		(pad "2" smd custom
			(at 0 0.4445 180)
			(size 0.1397 0.1397)
			(layers "F.Cu" "F.Mask" "F.Paste")
			(net "GND")
			(options
				(clearance outline)
				(anchor circle)
			)
			(primitives
				(gr_poly
					(pts
						(arc
							(start -0.1778 -0.2794)
							(mid -0.249642 -0.249642)
							(end -0.2794 -0.1778)
						)
						(arc
							(start -0.2794 0.1778)
							(mid -0.249642 0.249642)
							(end -0.1778 0.2794)
						)
						(arc
							(start 0.1778 0.2794)
							(mid 0.249642 0.249642)
							(end 0.2794 0.1778)
						)
						(arc
							(start 0.2794 -0.1778)
							(mid 0.249642 -0.249642)
							(end 0.1778 -0.2794)
						)
					)
					(width 0)
					(fill yes)
				)
			)
		)
	)
	(footprint ""
		(layer "F.Cu")
		(at 218.44 -381.762 180)
		(property "Reference" "R131"
			(at 0 0 180)
			(layer "F.SilkS")
			(hide yes)
			(effects
				(font
					(size 1.27 1.27)
				)
			)
		)
		(property "Value" "10KR2F-2-GP"
			(at 0.064008 -3.993896 180)
			(unlocked yes)
			(layer "F.Fab")
			(hide yes)
			(effects
				(font
					(size 1.016 1.016)
					(thickness 0.1524)
				)
			)
		)
		(property "Device Type" "R402H16"
			(at 0.064008 -5.517896 180)
			(unlocked yes)
			(layer "F.Fab")
			(hide yes)
			(effects
				(font
					(size 1.016 1.016)
					(thickness 0.1524)
				)
			)
		)
		(duplicate_pad_numbers_are_jumpers no)
		(fp_line
			(start 0.508 -0.9398)
			(end -0.508 -0.9398)
			(stroke
				(width 0.1524)
				(type default)
			)
			(layer "F.SilkS")
		)
		(fp_line
			(start -0.508 -0.9398)
			(end -0.508 0.9398)
			(stroke
				(width 0.1524)
				(type default)
			)
			(layer "F.SilkS")
		)
		(fp_rect
			(start -0.508 0.9398)
			(end 0.508 -0.9398)
			(stroke
				(width 0)
				(type default)
			)
			(fill no)
			(layer "F.CrtYd")
		)
		(fp_rect
			(start -0.508 0.9398)
			(end 0.508 -0.9398)
			(stroke
				(width 0)
				(type default)
			)
			(fill no)
			(layer "F.Fab")
		)
		(pad "1" smd custom
			(at 0 -0.4445 180)
			(size 0.1397 0.1397)
			(layers "F.Cu" "F.Mask" "F.Paste")
			(net "P5V_A_1")
			(options
				(clearance outline)
				(anchor circle)
			)
			(primitives
				(gr_poly
					(pts
						(arc
							(start -0.1778 -0.2794)
							(mid -0.249642 -0.249642)
							(end -0.2794 -0.1778)
						)
						(arc
							(start -0.2794 0.1778)
							(mid -0.249642 0.249642)
							(end -0.1778 0.2794)
						)
						(arc
							(start 0.1778 0.2794)
							(mid 0.249642 0.249642)
							(end 0.2794 0.1778)
						)
						(arc
							(start 0.2794 -0.1778)
							(mid 0.249642 -0.249642)
							(end 0.1778 -0.2794)
						)
					)
					(width 0)
					(fill yes)
				)
			)
		)
		(pad "2" smd custom
			(at 0 0.4445 180)
			(size 0.1397 0.1397)
			(layers "F.Cu" "F.Mask" "F.Paste")
			(net "SCC_FULL_PWR_EN_5V_R")
			(options
				(clearance outline)
				(anchor circle)
			)
			(primitives
				(gr_poly
					(pts
						(arc
							(start -0.1778 -0.2794)
							(mid -0.249642 -0.249642)
							(end -0.2794 -0.1778)
						)
						(arc
							(start -0.2794 0.1778)
							(mid -0.249642 0.249642)
							(end -0.1778 0.2794)
						)
						(arc
							(start 0.1778 0.2794)
							(mid 0.249642 0.249642)
							(end 0.2794 0.1778)
						)
						(arc
							(start 0.2794 -0.1778)
							(mid 0.249642 -0.249642)
							(end 0.1778 -0.2794)
						)
					)
					(width 0)
					(fill yes)
				)
			)
		)
	)
	(footprint ""
		(layer "F.Cu")
		(at 331.47 -176.127918 -90)
		(property "Reference" "R543"
			(at 0 0 270)
			(layer "F.SilkS")
			(hide yes)
			(effects
				(font
					(size 1.27 1.27)
				)
			)
		)
		(property "Value" "2R6F-GP"
			(at -0.0508 -4.8514 270)
			(unlocked yes)
			(layer "F.Fab")
			(hide yes)
			(effects
				(font
					(size 1.016 1.016)
					(thickness 0.1524)
				)
			)
		)
		(property "Device Type" "R1206H26"
			(at 0 -6.3754 270)
			(unlocked yes)
			(layer "F.Fab")
			(hide yes)
			(effects
				(font
					(size 1.016 1.016)
					(thickness 0.1524)
				)
			)
		)
		(duplicate_pad_numbers_are_jumpers no)
		(fp_line
			(start -1.016 2.2352)
			(end -1.016 -2.2352)
			(stroke
				(width 0.1524)
				(type default)
			)
			(layer "F.SilkS")
		)
		(fp_line
			(start 1.016 2.2352)
			(end -1.016 2.2352)
			(stroke
				(width 0.1524)
				(type default)
			)
			(layer "F.SilkS")
		)
		(fp_line
			(start -1.016 -2.2352)
			(end 1.016 -2.2352)
			(stroke
				(width 0.1524)
				(type default)
			)
			(layer "F.SilkS")
		)
		(fp_line
			(start 1.016 -2.2352)
			(end 1.016 2.2352)
			(stroke
				(width 0.1524)
				(type default)
			)
			(layer "F.SilkS")
		)
		(fp_rect
			(start -1.0922 2.3114)
			(end 1.0922 -2.3114)
			(stroke
				(width 0)
				(type default)
			)
			(fill no)
			(layer "F.CrtYd")
		)
		(fp_poly
			(pts
				(xy -1.0922 -2.3114) (xy 1.0922 -2.3114) (xy 1.0922 2.3114) (xy -1.0922 2.3114)
			)
			(stroke
				(width 0)
				(type default)
			)
			(fill no)
			(layer "F.Fab")
		)
		(pad "1" smd rect
			(at 0 -1.397 270)
			(size 1.651 1.27)
			(layers "F.Cu" "F.Mask" "F.Paste")
			(net "P5V_HDD18")
		)
		(pad "2" smd rect
			(at 0 1.397 270)
			(size 1.651 1.27)
			(layers "F.Cu" "F.Mask" "F.Paste")
			(net "5V_PRE_18")
		)
	)
	(footprint ""
		(layer "F.Cu")
		(at 111.795052 -127.254)
		(property "Reference" "R293"
			(at 0 0 0)
			(layer "F.SilkS")
			(hide yes)
			(effects
				(font
					(size 1.27 1.27)
				)
			)
		)
		(property "Value" "130R3F-GP"
			(at -0.0254 -2.5146 0)
			(unlocked yes)
			(layer "F.Fab")
			(hide yes)
			(effects
				(font
					(size 1.016 1.016)
					(thickness 0.1524)
				)
			)
		)
		(property "Device Type" "R603H22"
			(at -0.0254 -4.0386 0)
			(unlocked yes)
			(layer "F.Fab")
			(hide yes)
			(effects
				(font
					(size 1.016 1.016)
					(thickness 0.1524)
				)
			)
		)
		(duplicate_pad_numbers_are_jumpers no)
		(fp_line
			(start -0.4826 0)
			(end -0.2032 0)
			(stroke
				(width 0.2032)
				(type default)
			)
			(layer "F.SilkS")
		)
		(fp_line
			(start 0.2032 0)
			(end 0.4826 0)
			(stroke
				(width 0.2032)
				(type default)
			)
			(layer "F.SilkS")
		)
		(fp_rect
			(start -0.5842 1.3335)
			(end 0.5842 -1.3335)
			(stroke
				(width 0)
				(type default)
			)
			(fill no)
			(layer "F.CrtYd")
		)
		(fp_rect
			(start -0.5842 1.3335)
			(end 0.5842 -1.3335)
			(stroke
				(width 0)
				(type default)
			)
			(fill no)
			(layer "F.Fab")
		)
		(pad "1" smd custom
			(at 0 -0.762)
			(size 0.2159 0.2159)
			(layers "F.Cu" "F.Mask" "F.Paste")
			(net "P5V_A_2")
			(options
				(clearance outline)
				(anchor circle)
			)
			(primitives
				(gr_poly
					(pts
						(arc
							(start -0.3302 -0.4318)
							(mid -0.402042 -0.402042)
							(end -0.4318 -0.3302)
						)
						(arc
							(start -0.4318 0.3302)
							(mid -0.402042 0.402042)
							(end -0.3302 0.4318)
						)
						(arc
							(start 0.3302 0.4318)
							(mid 0.402042 0.402042)
							(end 0.4318 0.3302)
						)
						(arc
							(start 0.4318 -0.3302)
							(mid 0.402042 -0.402042)
							(end 0.3302 -0.4318)
						)
					)
					(width 0)
					(fill yes)
				)
			)
		)
		(pad "2" smd custom
			(at 0 0.762)
			(size 0.2159 0.2159)
			(layers "F.Cu" "F.Mask" "F.Paste")
			(net "FLT_HDD15")
			(options
				(clearance outline)
				(anchor circle)
			)
			(primitives
				(gr_poly
					(pts
						(arc
							(start -0.3302 -0.4318)
							(mid -0.402042 -0.402042)
							(end -0.4318 -0.3302)
						)
						(arc
							(start -0.4318 0.3302)
							(mid -0.402042 0.402042)
							(end -0.3302 0.4318)
						)
						(arc
							(start 0.3302 0.4318)
							(mid 0.402042 0.402042)
							(end 0.4318 0.3302)
						)
						(arc
							(start 0.4318 -0.3302)
							(mid 0.402042 -0.402042)
							(end 0.3302 -0.4318)
						)
					)
					(width 0)
					(fill yes)
				)
			)
		)
	)
	(footprint ""
		(layer "F.Cu")
		(at 42.667428 -127.798068 180)
		(property "Reference" "Q276"
			(at 0 0 180)
			(layer "F.SilkS")
			(hide yes)
			(effects
				(font
					(size 1.27 1.27)
				)
			)
		)
		(property "Value" "SSM3K324R-GP"
			(at 0.127 -8.9662 180)
			(unlocked yes)
			(layer "F.Fab")
			(hide yes)
			(effects
				(font
					(size 1.016 1.016)
					(thickness 0.1524)
				)
			)
		)
		(property "Device Type" "SOT23DGS2D4H35"
			(at 0.127 -10.4902 180)
			(unlocked yes)
			(layer "F.Fab")
			(hide yes)
			(effects
				(font
					(size 1.016 1.016)
					(thickness 0.1524)
				)
			)
		)
		(duplicate_pad_numbers_are_jumpers no)
		(fp_line
			(start 1.651 1.778)
			(end 1.651 -1.778)
			(stroke
				(width 0.1524)
				(type default)
			)
			(layer "F.SilkS")
		)
		(fp_line
			(start 1.651 -1.778)
			(end -1.651 -1.778)
			(stroke
				(width 0.1524)
				(type default)
			)
			(layer "F.SilkS")
		)
		(fp_line
			(start -1.651 1.778)
			(end 1.651 1.778)
			(stroke
				(width 0.1524)
				(type default)
			)
			(layer "F.SilkS")
		)
		(fp_line
			(start -1.651 -1.778)
			(end -1.651 1.778)
			(stroke
				(width 0.1524)
				(type default)
			)
			(layer "F.SilkS")
		)
		(fp_poly
			(pts
				(xy -1.778 1.8796) (xy -1.778 -1.8796) (xy 1.778 -1.8796) (xy 1.778 1.8796)
			)
			(stroke
				(width 0)
				(type default)
			)
			(fill no)
			(layer "F.CrtYd")
		)
		(fp_poly
			(pts
				(xy -1.778 1.8796) (xy -1.778 -1.8796) (xy 1.778 -1.8796) (xy 1.778 1.8796)
			)
			(stroke
				(width 0)
				(type default)
			)
			(fill no)
			(layer "F.Fab")
		)
		(pad "D" smd custom
			(at 0 -0.9525 180)
			(size 0.1905 0.1905)
			(layers "F.Cu" "F.Mask" "F.Paste")
			(net "DRV_ACT_13_N")
			(options
				(clearance outline)
				(anchor circle)
			)
			(primitives
				(gr_poly
					(pts
						(arc
							(start -0.1778 0.5715)
							(mid -0.321484 0.511984)
							(end -0.381 0.3683)
						)
						(arc
							(start -0.381 -0.3683)
							(mid -0.321484 -0.511984)
							(end -0.1778 -0.5715)
						)
						(arc
							(start 0.1778 -0.5715)
							(mid 0.321484 -0.511984)
							(end 0.381 -0.3683)
						)
						(arc
							(start 0.381 0.3683)
							(mid 0.321484 0.511984)
							(end 0.1778 0.5715)
						)
					)
					(width 0)
					(fill yes)
				)
			)
		)
		(pad "G" smd custom
			(at -0.98425 0.9525 180)
			(size 0.1905 0.1905)
			(layers "F.Cu" "F.Mask" "F.Paste")
			(net "DRIVE_A_13_ACT")
			(options
				(clearance outline)
				(anchor circle)
			)
			(primitives
				(gr_poly
					(pts
						(arc
							(start -0.1778 0.5715)
							(mid -0.321484 0.511984)
							(end -0.381 0.3683)
						)
						(arc
							(start -0.381 -0.3683)
							(mid -0.321484 -0.511984)
							(end -0.1778 -0.5715)
						)
						(arc
							(start 0.1778 -0.5715)
							(mid 0.321484 -0.511984)
							(end 0.381 -0.3683)
						)
						(arc
							(start 0.381 0.3683)
							(mid 0.321484 0.511984)
							(end 0.1778 0.5715)
						)
					)
					(width 0)
					(fill yes)
				)
			)
		)
		(pad "S" smd custom
			(at 0.98425 0.9525 180)
			(size 0.1905 0.1905)
			(layers "F.Cu" "F.Mask" "F.Paste")
			(net "GND")
			(options
				(clearance outline)
				(anchor circle)
			)
			(primitives
				(gr_poly
					(pts
						(arc
							(start -0.1778 0.5715)
							(mid -0.321484 0.511984)
							(end -0.381 0.3683)
						)
						(arc
							(start -0.381 -0.3683)
							(mid -0.321484 -0.511984)
							(end -0.1778 -0.5715)
						)
						(arc
							(start 0.1778 -0.5715)
							(mid 0.321484 -0.511984)
							(end 0.381 -0.3683)
						)
						(arc
							(start 0.381 0.3683)
							(mid 0.321484 0.511984)
							(end 0.1778 0.5715)
						)
					)
					(width 0)
					(fill yes)
				)
			)
		)
	)
)
